(kicad_pcb
	(version 20260206)
	(generator "pcbnew")
	(generator_version "10.0")
	(general
		(thickness 1.6)
		(legacy_teardrops no)
	)
	(paper "A4")
	(title_block
		(title "Bryce Canyon_SCC_16316-1_OCP.brd")
		(comment 1 "Bryce Canyon / footprint 482 of 1561 (U2), pads 850-896 of 896")
	)
	(layers
		(0 "F.Cu" signal "TOP")
		(4 "In1.Cu" signal "L2GND")
		(6 "In2.Cu" signal "L3")
		(8 "In3.Cu" signal "L4VCC")
		(10 "In4.Cu" signal "L5VCC")
		(12 "In5.Cu" signal "L6")
		(14 "In6.Cu" signal "L7GND")
		(2 "B.Cu" signal "BOTTOM")
		(9 "F.Adhes" user "F.Adhesive")
		(11 "B.Adhes" user "B.Adhesive")
		(13 "F.Paste" user "Package Geometry/Pastemask Top")
		(15 "B.Paste" user "Package Geometry/Pastemask Bottom")
		(5 "F.SilkS" user "Ref Des/Silkscreen Top")
		(7 "B.SilkS" user "Ref Des/Silkscreen Bottom")
		(1 "F.Mask" user "Board Geometry/Soldermask Top")
		(3 "B.Mask" user "Board Geometry/Soldermask Bottom")
		(17 "Dwgs.User" user "User.Drawings")
		(19 "Cmts.User" user "User.Comments")
		(21 "Eco1.User" user "User.Eco1")
		(23 "Eco2.User" user "User.Eco2")
		(25 "Edge.Cuts" user "Board Geometry/Outline")
		(27 "Margin" user)
		(31 "F.CrtYd" user "Package Geometry/Place Bound Top")
		(29 "B.CrtYd" user "Package Geometry/Place Bound Bottom")
		(35 "F.Fab" user "Ref Des/Assembly Top")
		(33 "B.Fab" user "Ref Des/Assembly Bottom")
	)
	(footprint ""
		(layer "F.Cu")
		(at 174.999904 -39.99992)
		(property "Reference" "U2"
			(at 0 0 0)
			(layer "F.SilkS")
			(hide yes)
			(effects
				(font
					(size 1.27 1.27)
				)
			)
		)
		(property "Value" "SAS3008C0-1-DB-500020657-1-GP"
			(at -20.374102 -5.0292 0)
			(unlocked yes)
			(layer "F.Fab")
			(hide yes)
			(effects
				(font
					(size 1.016 1.016)
					(thickness 0.1524)
				)
			)
		)
		(property "Device Type" "BGA896D25H78"
			(at -20.374102 -6.5532 0)
			(unlocked yes)
			(layer "F.Fab")
			(hide yes)
			(effects
				(font
					(size 1.016 1.016)
					(thickness 0.1524)
				)
			)
		)
		(duplicate_pad_numbers_are_jumpers no)
		(pad "W14" smd circle
			(at -1.199896 2.800096)
			(size 0.3556 0.3556)
			(layers "F.Cu" "F.Mask" "F.Paste")
			(net "P0V975")
		)
		(pad "W15" smd circle
			(at -0.40005 2.800096)
			(size 0.3556 0.3556)
			(layers "F.Cu" "F.Mask" "F.Paste")
			(net "GND")
		)
		(pad "W16" smd circle
			(at 0.40005 2.800096)
			(size 0.3556 0.3556)
			(layers "F.Cu" "F.Mask" "F.Paste")
			(net "P0V975")
		)
		(pad "W17" smd circle
			(at 1.199896 2.800096)
			(size 0.3556 0.3556)
			(layers "F.Cu" "F.Mask" "F.Paste")
			(net "GND")
		)
		(pad "W18" smd circle
			(at 1.999996 2.800096)
			(size 0.3556 0.3556)
			(layers "F.Cu" "F.Mask" "F.Paste")
			(net "P0V975")
		)
		(pad "W19" smd circle
			(at 2.800096 2.800096)
			(size 0.3556 0.3556)
			(layers "F.Cu" "F.Mask" "F.Paste")
			(net "GND")
		)
		(pad "W20" smd circle
			(at 3.599942 2.800096)
			(size 0.3556 0.3556)
			(layers "F.Cu" "F.Mask" "F.Paste")
			(net "P0V975")
		)
		(pad "W21" smd circle
			(at 4.400042 2.800096)
			(size 0.3556 0.3556)
			(layers "F.Cu" "F.Mask" "F.Paste")
			(net "GND")
		)
		(pad "W22" smd circle
			(at 5.199888 2.800096)
			(size 0.3556 0.3556)
			(layers "F.Cu" "F.Mask" "F.Paste")
			(net "GND")
		)
		(pad "W23" smd circle
			(at 5.999988 2.800096)
			(size 0.3556 0.3556)
			(layers "F.Cu" "F.Mask" "F.Paste")
			(net "GND")
		)
		(pad "W24" smd circle
			(at 6.800088 2.800096)
			(size 0.3556 0.3556)
			(layers "F.Cu" "F.Mask" "F.Paste")
			(net "GND")
		)
		(pad "W25" smd circle
			(at 7.599934 2.800096)
			(size 0.3556 0.3556)
			(layers "F.Cu" "F.Mask" "F.Paste")
			(net "GND")
		)
		(pad "W26" smd circle
			(at 8.400034 2.800096)
			(size 0.3556 0.3556)
			(layers "F.Cu" "F.Mask" "F.Paste")
			(net "GND")
		)
		(pad "W27" smd circle
			(at 9.19988 2.800096)
			(size 0.3556 0.3556)
			(layers "F.Cu" "F.Mask" "F.Paste")
			(net "P1V8_C")
		)
		(pad "W28" smd circle
			(at 9.99998 2.800096)
			(size 0.3556 0.3556)
			(layers "F.Cu" "F.Mask" "F.Paste")
			(net "IOC_GPIO_38")
		)
		(pad "W29" smd circle
			(at 10.80008 2.800096)
			(size 0.3556 0.3556)
			(layers "F.Cu" "F.Mask" "F.Paste")
			(net "I2C_IOC_4_SCL")
		)
		(pad "W30" smd circle
			(at 11.599926 2.800096)
			(size 0.3556 0.3556)
			(layers "F.Cu" "F.Mask" "F.Paste")
			(net "IOC_GPIO_24")
		)
		(pad "Y1" smd circle
			(at -11.599926 3.599942)
			(size 0.3556 0.3556)
			(layers "F.Cu" "F.Mask" "F.Paste")
			(net "SAS0_VDDH")
		)
		(pad "Y2" smd circle
			(at -10.80008 3.599942)
			(size 0.3556 0.3556)
			(layers "F.Cu" "F.Mask" "F.Paste")
			(net "GND")
		)
		(pad "Y3" smd circle
			(at -9.99998 3.599942)
			(size 0.3556 0.3556)
			(layers "F.Cu" "F.Mask" "F.Paste")
			(net "GND")
		)
		(pad "Y4" smd circle
			(at -9.19988 3.599942)
			(size 0.3556 0.3556)
			(layers "F.Cu" "F.Mask" "F.Paste")
			(net "SAS0_AVDD")
		)
		(pad "Y5" smd circle
			(at -8.400034 3.599942)
			(size 0.3556 0.3556)
			(layers "F.Cu" "F.Mask" "F.Paste")
			(net "GND")
		)
		(pad "Y6" smd circle
			(at -7.599934 3.599942)
			(size 0.3556 0.3556)
			(layers "F.Cu" "F.Mask" "F.Paste")
			(net "SAS0_VDDH")
		)
		(pad "Y7" smd circle
			(at -6.800088 3.599942)
			(size 0.3556 0.3556)
			(layers "F.Cu" "F.Mask" "F.Paste")
			(net "SAS0_AVDD")
		)
		(pad "Y8" smd circle
			(at -5.999988 3.599942)
			(size 0.3556 0.3556)
			(layers "F.Cu" "F.Mask" "F.Paste")
			(net "GND")
		)
		(pad "Y9" smd circle
			(at -5.199888 3.599942)
			(size 0.3556 0.3556)
			(layers "F.Cu" "F.Mask" "F.Paste")
			(net "GND")
		)
		(pad "Y10" smd circle
			(at -4.400042 3.599942)
			(size 0.3556 0.3556)
			(layers "F.Cu" "F.Mask" "F.Paste")
			(net "GND")
		)
		(pad "Y11" smd circle
			(at -3.599942 3.599942)
			(size 0.3556 0.3556)
			(layers "F.Cu" "F.Mask" "F.Paste")
			(net "GND")
		)
		(pad "Y12" smd circle
			(at -2.800096 3.599942)
			(size 0.3556 0.3556)
			(layers "F.Cu" "F.Mask" "F.Paste")
			(net "GND")
		)
		(pad "Y13" smd circle
			(at -1.999996 3.599942)
			(size 0.3556 0.3556)
			(layers "F.Cu" "F.Mask" "F.Paste")
			(net "GND")
		)
		(pad "Y14" smd circle
			(at -1.199896 3.599942)
			(size 0.3556 0.3556)
			(layers "F.Cu" "F.Mask" "F.Paste")
			(net "GND")
		)
		(pad "Y15" smd circle
			(at -0.40005 3.599942)
			(size 0.3556 0.3556)
			(layers "F.Cu" "F.Mask" "F.Paste")
			(net "GND")
		)
		(pad "Y16" smd circle
			(at 0.40005 3.599942)
			(size 0.3556 0.3556)
			(layers "F.Cu" "F.Mask" "F.Paste")
			(net "GND")
		)
		(pad "Y17" smd circle
			(at 1.199896 3.599942)
			(size 0.3556 0.3556)
			(layers "F.Cu" "F.Mask" "F.Paste")
			(net "P0V975")
		)
		(pad "Y18" smd circle
			(at 1.999996 3.599942)
			(size 0.3556 0.3556)
			(layers "F.Cu" "F.Mask" "F.Paste")
			(net "GND")
		)
		(pad "Y19" smd circle
			(at 2.800096 3.599942)
			(size 0.3556 0.3556)
			(layers "F.Cu" "F.Mask" "F.Paste")
			(net "P0V975")
		)
		(pad "Y20" smd circle
			(at 3.599942 3.599942)
			(size 0.3556 0.3556)
			(layers "F.Cu" "F.Mask" "F.Paste")
			(net "GND")
		)
		(pad "Y21" smd circle
			(at 4.400042 3.599942)
			(size 0.3556 0.3556)
			(layers "F.Cu" "F.Mask" "F.Paste")
			(net "P0V975")
		)
		(pad "Y22" smd circle
			(at 5.199888 3.599942)
			(size 0.3556 0.3556)
			(layers "F.Cu" "F.Mask" "F.Paste")
			(net "GND")
		)
		(pad "Y23" smd circle
			(at 5.999988 3.599942)
			(size 0.3556 0.3556)
			(layers "F.Cu" "F.Mask" "F.Paste")
			(net "GND")
		)
		(pad "Y24" smd circle
			(at 6.800088 3.599942)
			(size 0.3556 0.3556)
			(layers "F.Cu" "F.Mask" "F.Paste")
			(net "GND")
		)
		(pad "Y25" smd circle
			(at 7.599934 3.599942)
			(size 0.3556 0.3556)
			(layers "F.Cu" "F.Mask" "F.Paste")
			(net "GND")
		)
		(pad "Y26" smd circle
			(at 8.400034 3.599942)
			(size 0.3556 0.3556)
			(layers "F.Cu" "F.Mask" "F.Paste")
			(net "P1V8_C")
		)
		(pad "Y27" smd circle
			(at 9.19988 3.599942)
			(size 0.3556 0.3556)
			(layers "F.Cu" "F.Mask" "F.Paste")
			(net "GND")
		)
		(pad "Y28" smd circle
			(at 9.99998 3.599942)
			(size 0.3556 0.3556)
			(layers "F.Cu" "F.Mask" "F.Paste")
			(net "I2C_IOC_2_SDA")
		)
		(pad "Y29" smd circle
			(at 10.80008 3.599942)
			(size 0.3556 0.3556)
			(layers "F.Cu" "F.Mask" "F.Paste")
			(net "SPARE4")
		)
		(pad "Y30" smd circle
			(at 11.599926 3.599942)
			(size 0.3556 0.3556)
			(layers "F.Cu" "F.Mask" "F.Paste")
			(net "IOC_GPIO_15")
		)
	)
)
